(kicad_pcb
	(version 20260206)
	(generator "pcbnew")
	(generator_version "10.0")
	(general
		(thickness 1.6)
		(legacy_teardrops no)
	)
	(paper "A4")
	(title_block
		(title "peb — Lightning_PEB_BRD.brd")
		(comment 1 "Lightning (Wiwynn / Facebook NVMe JBOF) / footprints 2395-2401 of 2563")
	)
	(layers
		(0 "F.Cu" signal "TOP")
		(4 "In1.Cu" signal "L2GND")
		(6 "In2.Cu" signal "L3")
		(8 "In3.Cu" signal "L4VCC")
		(10 "In4.Cu" signal "L5VCC")
		(12 "In5.Cu" signal "L6")
		(14 "In6.Cu" signal "L7GND")
		(2 "B.Cu" signal "BOTTOM")
		(9 "F.Adhes" user "F.Adhesive")
		(11 "B.Adhes" user "B.Adhesive")
		(13 "F.Paste" user "Package Geometry/Pastemask Top")
		(15 "B.Paste" user "Package Geometry/Pastemask Bottom")
		(5 "F.SilkS" user "Ref Des/Silkscreen Top")
		(7 "B.SilkS" user "Ref Des/Silkscreen Bottom")
		(1 "F.Mask" user "Board Geometry/Soldermask Top")
		(3 "B.Mask" user "Board Geometry/Soldermask Bottom")
		(17 "Dwgs.User" user "User.Drawings")
		(19 "Cmts.User" user "User.Comments")
		(21 "Eco1.User" user "User.Eco1")
		(23 "Eco2.User" user "User.Eco2")
		(25 "Edge.Cuts" user "Board Geometry/Outline")
		(27 "Margin" user)
		(31 "F.CrtYd" user "Package Geometry/Place Bound Top")
		(29 "B.CrtYd" user "Package Geometry/Place Bound Bottom")
		(35 "F.Fab" user "Ref Des/Assembly Top")
		(33 "B.Fab" user "Ref Des/Assembly Bottom")
	)
	(footprint ""
		(layer "B.Cu")
		(at 230.1494 -41.9862 90)
		(property "Reference" "C575"
			(at 0 0 90)
			(layer "B.SilkS")
			(hide yes)
			(effects
				(font
					(size 1.27 1.27)
				)
				(justify mirror)
			)
		)
		(property "Value" "SCD1U16V1KX-1-GP"
			(at 2.8321 -1.7399 90)
			(unlocked yes)
			(layer "B.Fab")
			(hide yes)
			(effects
				(font
					(size 1.016 1.016)
					(thickness 0.1524)
				)
				(justify mirror)
			)
		)
		(property "Device Type" "C0201H13"
			(at 2.8321 -3.2639 90)
			(unlocked yes)
			(layer "B.Fab")
			(hide yes)
			(effects
				(font
					(size 1.016 1.016)
					(thickness 0.1524)
				)
				(justify mirror)
			)
		)
		(duplicate_pad_numbers_are_jumpers no)
		(fp_rect
			(start 0.2794 0.6477)
			(end -0.2794 -0.6477)
			(stroke
				(width 0)
				(type default)
			)
			(fill no)
			(layer "B.CrtYd")
		)
		(fp_rect
			(start 0.2794 0.6477)
			(end -0.2794 -0.6477)
			(stroke
				(width 0)
				(type default)
			)
			(fill no)
			(layer "B.Fab")
		)
		(pad "1" smd custom
			(at 0 -0.2794 270)
			(size 0.0762 0.0762)
			(layers "B.Cu" "B.Mask" "B.Paste")
			(net "DUT_AVD_PCIE")
			(options
				(clearance outline)
				(anchor circle)
			)
			(primitives
				(gr_poly
					(pts
						(arc
							(start 0.1524 0.127)
							(mid 0.137521 0.162921)
							(end 0.1016 0.1778)
						)
						(arc
							(start -0.1016 0.1778)
							(mid -0.137521 0.162921)
							(end -0.1524 0.127)
						)
						(arc
							(start -0.1524 -0.127)
							(mid -0.137521 -0.162921)
							(end -0.1016 -0.1778)
						)
						(arc
							(start 0.1016 -0.1778)
							(mid 0.137521 -0.162921)
							(end 0.1524 -0.127)
						)
					)
					(width 0)
					(fill yes)
				)
			)
		)
		(pad "2" smd custom
			(at 0 0.2794 270)
			(size 0.0762 0.0762)
			(layers "B.Cu" "B.Mask" "B.Paste")
			(net "GND")
			(options
				(clearance outline)
				(anchor circle)
			)
			(primitives
				(gr_poly
					(pts
						(arc
							(start 0.1524 0.127)
							(mid 0.137521 0.162921)
							(end 0.1016 0.1778)
						)
						(arc
							(start -0.1016 0.1778)
							(mid -0.137521 0.162921)
							(end -0.1524 0.127)
						)
						(arc
							(start -0.1524 -0.127)
							(mid -0.137521 -0.162921)
							(end -0.1016 -0.1778)
						)
						(arc
							(start 0.1016 -0.1778)
							(mid 0.137521 -0.162921)
							(end 0.1524 -0.127)
						)
					)
					(width 0)
					(fill yes)
				)
			)
		)
	)
	(footprint ""
		(layer "B.Cu")
		(at 228.195124 -203.047092 180)
		(property "Reference" "R4134"
			(at 0 0 0)
			(layer "B.SilkS")
			(hide yes)
			(effects
				(font
					(size 1.27 1.27)
				)
				(justify mirror)
			)
		)
		(property "Value" "4K7R2F-GP"
			(at -0.064008 -3.993896 180)
			(unlocked yes)
			(layer "B.Fab")
			(hide yes)
			(effects
				(font
					(size 1.016 1.016)
					(thickness 0.1524)
				)
				(justify mirror)
			)
		)
		(property "Device Type" "R402H16"
			(at -0.064008 -5.517896 180)
			(unlocked yes)
			(layer "B.Fab")
			(hide yes)
			(effects
				(font
					(size 1.016 1.016)
					(thickness 0.1524)
				)
				(justify mirror)
			)
		)
		(duplicate_pad_numbers_are_jumpers no)
		(fp_line
			(start 0.508 -0.9398)
			(end 0.508 0.9398)
			(stroke
				(width 0.1524)
				(type default)
			)
			(layer "B.SilkS")
		)
		(fp_line
			(start -0.508 -0.9398)
			(end 0.508 -0.9398)
			(stroke
				(width 0.1524)
				(type default)
			)
			(layer "B.SilkS")
		)
		(fp_rect
			(start 0.508 0.9398)
			(end -0.508 -0.9398)
			(stroke
				(width 0)
				(type default)
			)
			(fill no)
			(layer "B.CrtYd")
		)
		(fp_rect
			(start 0.508 0.9398)
			(end -0.508 -0.9398)
			(stroke
				(width 0)
				(type default)
			)
			(fill no)
			(layer "B.Fab")
		)
		(pad "1" smd custom
			(at 0 -0.4445)
			(size 0.1397 0.1397)
			(layers "B.Cu" "B.Mask" "B.Paste")
			(net "SSD_PRSNT#12")
			(options
				(clearance outline)
				(anchor circle)
			)
			(primitives
				(gr_poly
					(pts
						(arc
							(start -0.1778 0.2794)
							(mid -0.249642 0.249642)
							(end -0.2794 0.1778)
						)
						(arc
							(start -0.2794 -0.1778)
							(mid -0.249642 -0.249642)
							(end -0.1778 -0.2794)
						)
						(arc
							(start 0.1778 -0.2794)
							(mid 0.249642 -0.249642)
							(end 0.2794 -0.1778)
						)
						(arc
							(start 0.2794 0.1778)
							(mid 0.249642 0.249642)
							(end 0.1778 0.2794)
						)
					)
					(width 0)
					(fill yes)
				)
			)
		)
		(pad "2" smd custom
			(at 0 0.4445)
			(size 0.1397 0.1397)
			(layers "B.Cu" "B.Mask" "B.Paste")
			(net "P3V3_STBY")
			(options
				(clearance outline)
				(anchor circle)
			)
			(primitives
				(gr_poly
					(pts
						(arc
							(start -0.1778 0.2794)
							(mid -0.249642 0.249642)
							(end -0.2794 0.1778)
						)
						(arc
							(start -0.2794 -0.1778)
							(mid -0.249642 -0.249642)
							(end -0.1778 -0.2794)
						)
						(arc
							(start 0.1778 -0.2794)
							(mid 0.249642 -0.249642)
							(end 0.2794 -0.1778)
						)
						(arc
							(start 0.2794 0.1778)
							(mid 0.249642 0.249642)
							(end 0.1778 0.2794)
						)
					)
					(width 0)
					(fill yes)
				)
			)
		)
	)
	(footprint ""
		(layer "B.Cu")
		(at 227.965 -20.447)
		(property "Reference" "R3703"
			(at 0 0 0)
			(layer "B.SilkS")
			(hide yes)
			(effects
				(font
					(size 1.27 1.27)
				)
				(justify mirror)
			)
		)
		(property "Value" "4K7R2F-GP"
			(at -0.064008 -3.993896 0)
			(unlocked yes)
			(layer "B.Fab")
			(hide yes)
			(effects
				(font
					(size 1.016 1.016)
					(thickness 0.1524)
				)
				(justify mirror)
			)
		)
		(property "Device Type" "R402H16"
			(at -0.064008 -5.517896 0)
			(unlocked yes)
			(layer "B.Fab")
			(hide yes)
			(effects
				(font
					(size 1.016 1.016)
					(thickness 0.1524)
				)
				(justify mirror)
			)
		)
		(duplicate_pad_numbers_are_jumpers no)
		(fp_line
			(start -0.508 -0.9398)
			(end 0.508 -0.9398)
			(stroke
				(width 0.1524)
				(type default)
			)
			(layer "B.SilkS")
		)
		(fp_line
			(start 0.508 -0.9398)
			(end 0.508 0.9398)
			(stroke
				(width 0.1524)
				(type default)
			)
			(layer "B.SilkS")
		)
		(fp_rect
			(start 0.508 0.9398)
			(end -0.508 -0.9398)
			(stroke
				(width 0)
				(type default)
			)
			(fill no)
			(layer "B.CrtYd")
		)
		(fp_rect
			(start 0.508 0.9398)
			(end -0.508 -0.9398)
			(stroke
				(width 0)
				(type default)
			)
			(fill no)
			(layer "B.Fab")
		)
		(pad "1" smd custom
			(at 0 -0.4445 180)
			(size 0.1397 0.1397)
			(layers "B.Cu" "B.Mask" "B.Paste")
			(net "HOST3_RST_N_LS")
			(options
				(clearance outline)
				(anchor circle)
			)
			(primitives
				(gr_poly
					(pts
						(arc
							(start -0.1778 0.2794)
							(mid -0.249642 0.249642)
							(end -0.2794 0.1778)
						)
						(arc
							(start -0.2794 -0.1778)
							(mid -0.249642 -0.249642)
							(end -0.1778 -0.2794)
						)
						(arc
							(start 0.1778 -0.2794)
							(mid 0.249642 -0.249642)
							(end 0.2794 -0.1778)
						)
						(arc
							(start 0.2794 0.1778)
							(mid 0.249642 0.249642)
							(end 0.1778 0.2794)
						)
					)
					(width 0)
					(fill yes)
				)
			)
		)
		(pad "2" smd custom
			(at 0 0.4445 180)
			(size 0.1397 0.1397)
			(layers "B.Cu" "B.Mask" "B.Paste")
			(net "DUT_VDDO")
			(options
				(clearance outline)
				(anchor circle)
			)
			(primitives
				(gr_poly
					(pts
						(arc
							(start -0.1778 0.2794)
							(mid -0.249642 0.249642)
							(end -0.2794 0.1778)
						)
						(arc
							(start -0.2794 -0.1778)
							(mid -0.249642 -0.249642)
							(end -0.1778 -0.2794)
						)
						(arc
							(start 0.1778 -0.2794)
							(mid 0.249642 -0.249642)
							(end 0.2794 -0.1778)
						)
						(arc
							(start 0.2794 0.1778)
							(mid 0.249642 0.249642)
							(end 0.1778 0.2794)
						)
					)
					(width 0)
					(fill yes)
				)
			)
		)
	)
	(footprint ""
		(layer "B.Cu")
		(at 215.55964 -200.02246 180)
		(property "Reference" "C8092"
			(at 0 0 0)
			(layer "B.SilkS")
			(hide yes)
			(effects
				(font
					(size 1.27 1.27)
				)
				(justify mirror)
			)
		)
		(property "Value" "SCD047U25V2KX-GP"
			(at -1.1811 -2.7051 180)
			(unlocked yes)
			(layer "B.Fab")
			(hide yes)
			(effects
				(font
					(size 1.016 1.016)
					(thickness 0.1524)
				)
				(justify mirror)
			)
		)
		(property "Device Type" "C402H22"
			(at -1.1811 -4.2291 180)
			(unlocked yes)
			(layer "B.Fab")
			(hide yes)
			(effects
				(font
					(size 1.016 1.016)
					(thickness 0.1524)
				)
				(justify mirror)
			)
		)
		(duplicate_pad_numbers_are_jumpers no)
		(fp_rect
			(start 0.4318 0.9525)
			(end -0.4318 -0.9525)
			(stroke
				(width 0)
				(type default)
			)
			(fill no)
			(layer "B.CrtYd")
		)
		(fp_rect
			(start 0.4318 0.9525)
			(end -0.4318 -0.9525)
			(stroke
				(width 0)
				(type default)
			)
			(fill no)
			(layer "B.Fab")
		)
		(pad "1" smd custom
			(at 0 -0.4445)
			(size 0.1524 0.1524)
			(layers "B.Cu" "B.Mask" "B.Paste")
			(net "P3V3_STBY")
			(options
				(clearance outline)
				(anchor circle)
			)
			(primitives
				(gr_poly
					(pts
						(arc
							(start 0.3048 0.2032)
							(mid 0.275042 0.275042)
							(end 0.2032 0.3048)
						)
						(arc
							(start -0.2032 0.3048)
							(mid -0.275042 0.275042)
							(end -0.3048 0.2032)
						)
						(arc
							(start -0.3048 -0.2032)
							(mid -0.275042 -0.275042)
							(end -0.2032 -0.3048)
						)
						(arc
							(start 0.2032 -0.3048)
							(mid 0.275042 -0.275042)
							(end 0.3048 -0.2032)
						)
					)
					(width 0)
					(fill yes)
				)
			)
		)
		(pad "2" smd custom
			(at 0 0.4445)
			(size 0.1524 0.1524)
			(layers "B.Cu" "B.Mask" "B.Paste")
			(net "GND")
			(options
				(clearance outline)
				(anchor circle)
			)
			(primitives
				(gr_poly
					(pts
						(arc
							(start 0.3048 0.2032)
							(mid 0.275042 0.275042)
							(end 0.2032 0.3048)
						)
						(arc
							(start -0.2032 0.3048)
							(mid -0.275042 0.275042)
							(end -0.3048 0.2032)
						)
						(arc
							(start -0.3048 -0.2032)
							(mid -0.275042 -0.275042)
							(end -0.2032 -0.3048)
						)
						(arc
							(start 0.2032 -0.3048)
							(mid 0.275042 -0.275042)
							(end 0.3048 -0.2032)
						)
					)
					(width 0)
					(fill yes)
				)
			)
		)
	)
	(footprint ""
		(layer "B.Cu")
		(at 234.823 -20.447)
		(property "Reference" "R809"
			(at 0 0 0)
			(layer "B.SilkS")
			(hide yes)
			(effects
				(font
					(size 1.27 1.27)
				)
				(justify mirror)
			)
		)
		(property "Value" "4K7R2F-GP"
			(at -0.064008 -3.993896 0)
			(unlocked yes)
			(layer "B.Fab")
			(hide yes)
			(effects
				(font
					(size 1.016 1.016)
					(thickness 0.1524)
				)
				(justify mirror)
			)
		)
		(property "Device Type" "R402H16"
			(at -0.064008 -5.517896 0)
			(unlocked yes)
			(layer "B.Fab")
			(hide yes)
			(effects
				(font
					(size 1.016 1.016)
					(thickness 0.1524)
				)
				(justify mirror)
			)
		)
		(duplicate_pad_numbers_are_jumpers no)
		(fp_line
			(start -0.508 -0.9398)
			(end 0.508 -0.9398)
			(stroke
				(width 0.1524)
				(type default)
			)
			(layer "B.SilkS")
		)
		(fp_line
			(start 0.508 -0.9398)
			(end 0.508 0.9398)
			(stroke
				(width 0.1524)
				(type default)
			)
			(layer "B.SilkS")
		)
		(fp_rect
			(start 0.508 0.9398)
			(end -0.508 -0.9398)
			(stroke
				(width 0)
				(type default)
			)
			(fill no)
			(layer "B.CrtYd")
		)
		(fp_rect
			(start 0.508 0.9398)
			(end -0.508 -0.9398)
			(stroke
				(width 0)
				(type default)
			)
			(fill no)
			(layer "B.Fab")
		)
		(pad "1" smd custom
			(at 0 -0.4445 180)
			(size 0.1397 0.1397)
			(layers "B.Cu" "B.Mask" "B.Paste")
			(net "BOOTSTRAP4")
			(options
				(clearance outline)
				(anchor circle)
			)
			(primitives
				(gr_poly
					(pts
						(arc
							(start -0.1778 0.2794)
							(mid -0.249642 0.249642)
							(end -0.2794 0.1778)
						)
						(arc
							(start -0.2794 -0.1778)
							(mid -0.249642 -0.249642)
							(end -0.1778 -0.2794)
						)
						(arc
							(start 0.1778 -0.2794)
							(mid 0.249642 -0.249642)
							(end 0.2794 -0.1778)
						)
						(arc
							(start 0.2794 0.1778)
							(mid 0.249642 0.249642)
							(end 0.1778 0.2794)
						)
					)
					(width 0)
					(fill yes)
				)
			)
		)
		(pad "2" smd custom
			(at 0 0.4445 180)
			(size 0.1397 0.1397)
			(layers "B.Cu" "B.Mask" "B.Paste")
			(net "DUT_VDDO")
			(options
				(clearance outline)
				(anchor circle)
			)
			(primitives
				(gr_poly
					(pts
						(arc
							(start -0.1778 0.2794)
							(mid -0.249642 0.249642)
							(end -0.2794 0.1778)
						)
						(arc
							(start -0.2794 -0.1778)
							(mid -0.249642 -0.249642)
							(end -0.1778 -0.2794)
						)
						(arc
							(start 0.1778 -0.2794)
							(mid 0.249642 -0.249642)
							(end 0.2794 -0.1778)
						)
						(arc
							(start 0.2794 0.1778)
							(mid 0.249642 0.249642)
							(end 0.1778 0.2794)
						)
					)
					(width 0)
					(fill yes)
				)
			)
		)
	)
	(footprint ""
		(layer "B.Cu")
		(at 61.8236 -118.0084)
		(property "Reference" "U13"
			(at 0 0 0)
			(layer "B.SilkS")
			(hide yes)
			(effects
				(font
					(size 1.27 1.27)
				)
				(justify mirror)
			)
		)
		(property "Value" "2N7002DW-7F-GP"
			(at 2.3622 -8.2042 0)
			(unlocked yes)
			(layer "B.Fab")
			(hide yes)
			(effects
				(font
					(size 1.016 1.016)
					(thickness 0.1524)
				)
				(justify mirror)
			)
		)
		(property "Device Type" "SOT-363H44"
			(at 2.3622 -10.1092 0)
			(unlocked yes)
			(layer "B.Fab")
			(hide yes)
			(effects
				(font
					(size 1.016 1.016)
					(thickness 0.1524)
				)
				(justify mirror)
			)
		)
		(duplicate_pad_numbers_are_jumpers no)
		(fp_line
			(start -1.4478 -1.7018)
			(end 1.4478 -1.7018)
			(stroke
				(width 0.1524)
				(type default)
			)
			(layer "B.SilkS")
		)
		(fp_line
			(start -1.4478 1.7018)
			(end -1.4478 -1.7018)
			(stroke
				(width 0.1524)
				(type default)
			)
			(layer "B.SilkS")
		)
		(fp_line
			(start 1.27 1.524)
			(end 1.27 0.6604)
			(stroke
				(width 0.4826)
				(type default)
			)
			(layer "B.SilkS")
		)
		(fp_line
			(start 1.4478 -1.7018)
			(end 1.4478 1.7018)
			(stroke
				(width 0.1524)
				(type default)
			)
			(layer "B.SilkS")
		)
		(fp_line
			(start 1.4478 1.7018)
			(end -1.4478 1.7018)
			(stroke
				(width 0.1524)
				(type default)
			)
			(layer "B.SilkS")
		)
		(fp_poly
			(pts
				(xy 1.524 -1.778) (xy -1.524 -1.778) (xy -1.524 1.778) (xy 1.524 1.778)
			)
			(stroke
				(width 0)
				(type default)
			)
			(fill no)
			(layer "B.CrtYd")
		)
		(fp_poly
			(pts
				(xy 1.524 -1.778) (xy -1.524 -1.778) (xy -1.524 1.778) (xy 1.524 1.778)
			)
			(stroke
				(width 0)
				(type default)
			)
			(fill no)
			(layer "B.Fab")
		)
		(pad "1" smd rect
			(at 0.65024 0.9398 180)
			(size 0.4064 1.016)
			(layers "B.Cu" "B.Mask" "B.Paste")
			(net "BMC_I2C3_MINI3_SCL_S")
		)
		(pad "2" smd rect
			(at 0 0.9398 180)
			(size 0.4064 1.016)
			(layers "B.Cu" "B.Mask" "B.Paste")
			(net "I2C3_LS_G2")
		)
		(pad "3" smd rect
			(at -0.65024 0.9398 180)
			(size 0.4064 1.016)
			(layers "B.Cu" "B.Mask" "B.Paste")
			(net "BMC_I2C3_MINI3_SDA")
		)
		(pad "4" smd rect
			(at -0.65024 -0.9398 180)
			(size 0.4064 1.016)
			(layers "B.Cu" "B.Mask" "B.Paste")
			(net "BMC_I2C3_MINI3_SDA_S")
		)
		(pad "5" smd rect
			(at 0 -0.9398 180)
			(size 0.4064 1.016)
			(layers "B.Cu" "B.Mask" "B.Paste")
			(net "I2C3_LS_G1")
		)
		(pad "6" smd rect
			(at 0.65024 -0.9398 180)
			(size 0.4064 1.016)
			(layers "B.Cu" "B.Mask" "B.Paste")
			(net "BMC_I2C3_MINI3_SCL")
		)
	)
	(footprint ""
		(layer "B.Cu")
		(at 159.909002 -60.479432 -90)
		(property "Reference" "PR159"
			(at 0 0 90)
			(layer "B.SilkS")
			(hide yes)
			(effects
				(font
					(size 1.27 1.27)
				)
				(justify mirror)
			)
		)
		(property "Value" "0R3J-0-U-GP"
			(at 0.0254 -2.5146 270)
			(unlocked yes)
			(layer "B.Fab")
			(hide yes)
			(effects
				(font
					(size 1.016 1.016)
					(thickness 0.1524)
				)
				(justify mirror)
			)
		)
		(property "Device Type" "R603H22"
			(at 0.0254 -4.0386 270)
			(unlocked yes)
			(layer "B.Fab")
			(hide yes)
			(effects
				(font
					(size 1.016 1.016)
					(thickness 0.1524)
				)
				(justify mirror)
			)
		)
		(duplicate_pad_numbers_are_jumpers no)
		(fp_line
			(start -0.2032 0)
			(end -0.4826 0)
			(stroke
				(width 0.2032)
				(type default)
			)
			(layer "B.SilkS")
		)
		(fp_line
			(start 0.4826 0)
			(end 0.2032 0)
			(stroke
				(width 0.2032)
				(type default)
			)
			(layer "B.SilkS")
		)
		(fp_rect
			(start 0.5842 1.3335)
			(end -0.5842 -1.3335)
			(stroke
				(width 0)
				(type default)
			)
			(fill no)
			(layer "B.CrtYd")
		)
		(fp_rect
			(start 0.5842 1.3335)
			(end -0.5842 -1.3335)
			(stroke
				(width 0)
				(type default)
			)
			(fill no)
			(layer "B.Fab")
		)
		(pad "1" smd custom
			(at 0 -0.762 90)
			(size 0.2159 0.2159)
			(layers "B.Cu" "B.Mask" "B.Paste")
			(net "P0V9_LX")
			(options
				(clearance outline)
				(anchor circle)
			)
			(primitives
				(gr_poly
					(pts
						(arc
							(start -0.3302 0.4318)
							(mid -0.402042 0.402042)
							(end -0.4318 0.3302)
						)
						(arc
							(start -0.4318 -0.3302)
							(mid -0.402042 -0.402042)
							(end -0.3302 -0.4318)
						)
						(arc
							(start 0.3302 -0.4318)
							(mid 0.402042 -0.402042)
							(end 0.4318 -0.3302)
						)
						(arc
							(start 0.4318 0.3302)
							(mid 0.402042 0.402042)
							(end 0.3302 0.4318)
						)
					)
					(width 0)
					(fill yes)
				)
			)
		)
		(pad "2" smd custom
			(at 0 0.762 90)
			(size 0.2159 0.2159)
			(layers "B.Cu" "B.Mask" "B.Paste")
			(net "P0V9_VBST_RC")
			(options
				(clearance outline)
				(anchor circle)
			)
			(primitives
				(gr_poly
					(pts
						(arc
							(start -0.3302 0.4318)
							(mid -0.402042 0.402042)
							(end -0.4318 0.3302)
						)
						(arc
							(start -0.4318 -0.3302)
							(mid -0.402042 -0.402042)
							(end -0.3302 -0.4318)
						)
						(arc
							(start 0.3302 -0.4318)
							(mid 0.402042 -0.402042)
							(end 0.4318 -0.3302)
						)
						(arc
							(start 0.4318 0.3302)
							(mid 0.402042 0.402042)
							(end 0.3302 0.4318)
						)
					)
					(width 0)
					(fill yes)
				)
			)
		)
	)
)
